(kicad_pcb
	(version 20260206)
	(generator "pcbnew")
	(generator_version "10.0")
	(general
		(thickness 1.6)
		(legacy_teardrops no)
	)
	(paper "A4")
	(title_block
		(title "04192023_DAF0TMB3IC0_F0TG_MB_C_brd_V02_OCP.brd")
		(comment 1 "Grand Teton / footprint 3955 of 8354 (U25), pads 1200-1313 of 6102")
	)
	(layers
		(0 "F.Cu" signal "TOP")
		(4 "In1.Cu" signal "GND")
		(6 "In2.Cu" signal "IN1")
		(8 "In3.Cu" signal "GND1")
		(10 "In4.Cu" signal "IN2")
		(12 "In5.Cu" signal "GND2")
		(14 "In6.Cu" signal "IN3")
		(16 "In7.Cu" signal "GND3")
		(18 "In8.Cu" signal "VCC")
		(20 "In9.Cu" signal "VCC1")
		(22 "In10.Cu" signal "GND4")
		(24 "In11.Cu" signal "IN4")
		(26 "In12.Cu" signal "GND5")
		(28 "In13.Cu" signal "IN5")
		(30 "In14.Cu" signal "GND6")
		(32 "In15.Cu" signal "IN6")
		(34 "In16.Cu" signal "GND7")
		(2 "B.Cu" signal "BOTTOM")
		(9 "F.Adhes" user "F.Adhesive")
		(11 "B.Adhes" user "B.Adhesive")
		(13 "F.Paste" user "Package Geometry/Pastemask Top")
		(15 "B.Paste" user "Package Geometry/Pastemask Bottom")
		(5 "F.SilkS" user "Ref Des/Silkscreen Top")
		(7 "B.SilkS" user "Ref Des/Silkscreen Bottom")
		(1 "F.Mask" user "Board Geometry/Soldermask Top")
		(3 "B.Mask" user "Board Geometry/Soldermask Bottom")
		(17 "Dwgs.User" user "User.Drawings")
		(19 "Cmts.User" user "User.Comments")
		(21 "Eco1.User" user "User.Eco1")
		(23 "Eco2.User" user "User.Eco2")
		(25 "Edge.Cuts" user "Board Geometry/Outline")
		(27 "Margin" user)
		(31 "F.CrtYd" user "Package Geometry/Place Bound Top")
		(29 "B.CrtYd" user "Package Geometry/Place Bound Bottom")
		(35 "F.Fab" user "Ref Des/Assembly Top")
		(33 "B.Fab" user "Ref Des/Assembly Bottom")
	)
	(footprint ""
		(layer "F.Cu")
		(at 359.867962 -258.880102 180)
		(property "Reference" "U25"
			(at -45.78477 -62.086744 0)
			(unlocked yes)
			(layer "F.SilkS")
			(effects
				(font
					(size 0.7874 0.5842)
					(thickness 0.1524)
				)
			)
		)
		(property "Value" ""
			(at 0 0 180)
			(layer "F.Fab")
			(effects
				(font
					(size 1.27 1.27)
				)
			)
		)
		(duplicate_pad_numbers_are_jumpers no)
		(pad "AT60" smd circle
			(at 20.830032 -8.459978 180)
			(size 0.450088 0.450088)
			(layers "F.Cu" "F.Mask" "F.Paste")
			(net "GND")
		)
		(pad "AT61" smd circle
			(at 21.770086 -8.459978 180)
			(size 0.450088 0.450088)
			(layers "F.Cu" "F.Mask" "F.Paste")
			(net "GND")
		)
		(pad "AT62" smd circle
			(at 22.709886 -8.459978 180)
			(size 0.450088 0.450088)
			(layers "F.Cu" "F.Mask" "F.Paste")
			(net "M_B_CPU0_ALERT_R_N")
		)
		(pad "AT63" smd circle
			(at 23.64994 -8.459978 180)
			(size 0.450088 0.450088)
			(layers "F.Cu" "F.Mask" "F.Paste")
			(net "GND")
		)
		(pad "AT64" smd circle
			(at 24.589994 -8.459978 180)
			(size 0.450088 0.450088)
			(layers "F.Cu" "F.Mask" "F.Paste")
			(net "GND")
		)
		(pad "AT65" smd circle
			(at 25.530048 -8.459978 180)
			(size 0.450088 0.450088)
			(layers "F.Cu" "F.Mask" "F.Paste")
			(net "M_F_CPU0_ALERT_R_N")
		)
		(pad "AT66" smd circle
			(at 26.470102 -8.459978 180)
			(size 0.450088 0.450088)
			(layers "F.Cu" "F.Mask" "F.Paste")
			(net "GND")
		)
		(pad "AT67" smd circle
			(at 27.409902 -8.459978 180)
			(size 0.450088 0.450088)
			(layers "F.Cu" "F.Mask" "F.Paste")
			(net "GND")
		)
		(pad "AT68" smd circle
			(at 28.349956 -8.459978 180)
			(size 0.450088 0.450088)
			(layers "F.Cu" "F.Mask" "F.Paste")
			(net "GND")
		)
		(pad "AT69" smd circle
			(at 29.29001 -8.459978 180)
			(size 0.450088 0.450088)
			(layers "F.Cu" "F.Mask" "F.Paste")
			(net "M_E_CPU0_ALERT_R_N")
		)
		(pad "AT70" smd circle
			(at 30.230064 -8.459978 180)
			(size 0.450088 0.450088)
			(layers "F.Cu" "F.Mask" "F.Paste")
			(net "GND")
		)
		(pad "AT71" smd circle
			(at 31.170118 -8.459978 180)
			(size 0.450088 0.450088)
			(layers "F.Cu" "F.Mask" "F.Paste")
			(net "GND")
		)
		(pad "AT72" smd circle
			(at 32.109918 -8.459978 180)
			(size 0.450088 0.450088)
			(layers "F.Cu" "F.Mask" "F.Paste")
			(net "GND")
		)
		(pad "AT73" smd circle
			(at 33.049972 -8.459978 180)
			(size 0.450088 0.450088)
			(layers "F.Cu" "F.Mask" "F.Paste")
			(net "GND")
		)
		(pad "AT74" smd circle
			(at 33.990026 -8.459978 180)
			(size 0.450088 0.450088)
			(layers "F.Cu" "F.Mask" "F.Paste")
			(net "M_A_CPU0_RESET_N")
		)
		(pad "AU1" smd circle
			(at -34.159952 -7.649972 180)
			(size 0.450088 0.450088)
			(layers "F.Cu" "F.Mask" "F.Paste")
			(net "GND")
		)
		(pad "AU2" smd circle
			(at -33.219898 -7.649972 180)
			(size 0.450088 0.450088)
			(layers "F.Cu" "F.Mask" "F.Paste")
			(net "M_G_CPU0_SA_CS_N<0>")
		)
		(pad "AU3" smd circle
			(at -32.280098 -7.649972 180)
			(size 0.450088 0.450088)
			(layers "F.Cu" "F.Mask" "F.Paste")
			(net "GND")
		)
		(pad "AU4" smd circle
			(at -31.340044 -7.649972 180)
			(size 0.450088 0.450088)
			(layers "F.Cu" "F.Mask" "F.Paste")
			(net "GND")
		)
		(pad "AU5" smd circle
			(at -30.39999 -7.649972 180)
			(size 0.450088 0.450088)
			(layers "F.Cu" "F.Mask" "F.Paste")
			(net "M_K_CPU0_SA_CS_N<0>")
		)
		(pad "AU6" smd circle
			(at -29.459936 -7.649972 180)
			(size 0.450088 0.450088)
			(layers "F.Cu" "F.Mask" "F.Paste")
			(net "GND")
		)
		(pad "AU7" smd circle
			(at -28.519882 -7.649972 180)
			(size 0.450088 0.450088)
			(layers "F.Cu" "F.Mask" "F.Paste")
			(net "M_K_CPU0_RESET_N")
		)
		(pad "AU8" smd circle
			(at -27.580082 -7.649972 180)
			(size 0.450088 0.450088)
			(layers "F.Cu" "F.Mask" "F.Paste")
			(net "GND")
		)
		(pad "AU9" smd circle
			(at -26.640028 -7.649972 180)
			(size 0.450088 0.450088)
			(layers "F.Cu" "F.Mask" "F.Paste")
			(net "M_L_CPU0_SA_CS_N<0>")
		)
		(pad "AU10" smd circle
			(at -25.699974 -7.649972 180)
			(size 0.450088 0.450088)
			(layers "F.Cu" "F.Mask" "F.Paste")
			(net "M_L_CPU0_RESET_N")
		)
		(pad "AU11" smd circle
			(at -24.75992 -7.649972 180)
			(size 0.450088 0.450088)
			(layers "F.Cu" "F.Mask" "F.Paste")
			(net "GND")
		)
		(pad "AU12" smd circle
			(at -23.82012 -7.649972 180)
			(size 0.450088 0.450088)
			(layers "F.Cu" "F.Mask" "F.Paste")
			(net "M_H_CPU0_SA_CS_N<0>")
		)
		(pad "AU13" smd circle
			(at -22.880066 -7.649972 180)
			(size 0.450088 0.450088)
			(layers "F.Cu" "F.Mask" "F.Paste")
			(net "GND")
		)
		(pad "AU14" smd circle
			(at -21.940012 -7.649972 180)
			(size 0.450088 0.450088)
			(layers "F.Cu" "F.Mask" "F.Paste")
			(net "M_H_CPU0_RESET_N")
		)
		(pad "AU15" smd circle
			(at -20.999958 -7.649972 180)
			(size 0.450088 0.450088)
			(layers "F.Cu" "F.Mask" "F.Paste")
			(net "GND")
		)
		(pad "AU16" smd circle
			(at -20.059904 -7.649972 180)
			(size 0.450088 0.450088)
			(layers "F.Cu" "F.Mask" "F.Paste")
			(net "M_J_CPU0_SA_CS_N<0>")
		)
		(pad "AU17" smd circle
			(at -19.120104 -7.649972 180)
			(size 0.450088 0.450088)
			(layers "F.Cu" "F.Mask" "F.Paste")
			(net "M_J_CPU0_RESET_N")
		)
		(pad "AU18" smd circle
			(at -18.18005 -7.649972 180)
			(size 0.450088 0.450088)
			(layers "F.Cu" "F.Mask" "F.Paste")
			(net "GND")
		)
		(pad "AU19" smd circle
			(at -17.239996 -7.649972 180)
			(size 0.450088 0.450088)
			(layers "F.Cu" "F.Mask" "F.Paste")
			(net "M_I_CPU0_SA_CS_N<0>")
		)
		(pad "AU20" smd circle
			(at -16.299942 -7.649972 180)
			(size 0.450088 0.450088)
			(layers "F.Cu" "F.Mask" "F.Paste")
			(net "GND")
		)
		(pad "AU21" smd circle
			(at -15.359888 -7.649972 180)
			(size 0.450088 0.450088)
			(layers "F.Cu" "F.Mask" "F.Paste")
			(net "M_I_CPU0_RESET_N")
		)
		(pad "AU22" smd circle
			(at -14.420088 -7.649972 180)
			(size 0.450088 0.450088)
			(layers "F.Cu" "F.Mask" "F.Paste")
			(net "GND")
		)
		(pad "AU23" smd circle
			(at -13.480034 -7.649972 180)
			(size 0.450088 0.450088)
			(layers "F.Cu" "F.Mask" "F.Paste")
			(net "PVDDCR_SOC_P0")
		)
		(pad "AU24" smd circle
			(at -12.53998 -7.649972 180)
			(size 0.450088 0.450088)
			(layers "F.Cu" "F.Mask" "F.Paste")
			(net "GND")
		)
		(pad "AU25" smd circle
			(at -11.599926 -7.649972 180)
			(size 0.450088 0.450088)
			(layers "F.Cu" "F.Mask" "F.Paste")
			(net "PVDDCR_CPU0_P0")
		)
		(pad "AU26" smd circle
			(at -10.659872 -7.649972 180)
			(size 0.450088 0.450088)
			(layers "F.Cu" "F.Mask" "F.Paste")
			(net "GND")
		)
		(pad "AU27" smd circle
			(at -9.720072 -7.649972 180)
			(size 0.450088 0.450088)
			(layers "F.Cu" "F.Mask" "F.Paste")
			(net "PVDDCR_SOC_P0")
		)
		(pad "AU28" smd circle
			(at -8.780018 -7.649972 180)
			(size 0.450088 0.450088)
			(layers "F.Cu" "F.Mask" "F.Paste")
			(net "GND")
		)
		(pad "AU29" smd circle
			(at -7.839964 -7.649972 180)
			(size 0.450088 0.450088)
			(layers "F.Cu" "F.Mask" "F.Paste")
			(net "PVDDCR_CPU0_P0")
		)
		(pad "AU30" smd circle
			(at -6.89991 -7.649972 180)
			(size 0.450088 0.450088)
			(layers "F.Cu" "F.Mask" "F.Paste")
			(net "GND")
		)
		(pad "AU31" smd circle
			(at -5.96011 -7.649972 180)
			(size 0.450088 0.450088)
			(layers "F.Cu" "F.Mask" "F.Paste")
			(net "PVDDCR_SOC_P0")
		)
		(pad "AU32" smd circle
			(at -5.020056 -7.649972 180)
			(size 0.450088 0.450088)
			(layers "F.Cu" "F.Mask" "F.Paste")
			(net "GND")
		)
		(pad "AU33" smd circle
			(at -4.080002 -7.649972 180)
			(size 0.450088 0.450088)
			(layers "F.Cu" "F.Mask" "F.Paste")
			(net "PVDDCR_CPU0_P0")
		)
		(pad "AU34" smd circle
			(at -3.139948 -7.649972 180)
			(size 0.450088 0.450088)
			(layers "F.Cu" "F.Mask" "F.Paste")
			(net "GND")
		)
		(pad "AU35" smd circle
			(at -2.199894 -7.649972 180)
			(size 0.450088 0.450088)
			(layers "F.Cu" "F.Mask" "F.Paste")
			(net "PVDDCR_SOC_P0")
		)
		(pad "AU36" smd circle
			(at -1.260094 -7.649972 180)
			(size 0.450088 0.450088)
			(layers "F.Cu" "F.Mask" "F.Paste")
			(net "GND")
		)
		(pad "AU40" smd circle
			(at 1.560068 -7.649972 180)
			(size 0.450088 0.450088)
			(layers "F.Cu" "F.Mask" "F.Paste")
			(net "PVDDCR_SOC_P0")
		)
		(pad "AU41" smd circle
			(at 2.500122 -7.649972 180)
			(size 0.450088 0.450088)
			(layers "F.Cu" "F.Mask" "F.Paste")
			(net "GND")
		)
		(pad "AU42" smd circle
			(at 3.439922 -7.649972 180)
			(size 0.450088 0.450088)
			(layers "F.Cu" "F.Mask" "F.Paste")
			(net "PVDDCR_CPU0_P0")
		)
		(pad "AU43" smd circle
			(at 4.379976 -7.649972 180)
			(size 0.450088 0.450088)
			(layers "F.Cu" "F.Mask" "F.Paste")
			(net "GND")
		)
		(pad "AU44" smd circle
			(at 5.32003 -7.649972 180)
			(size 0.450088 0.450088)
			(layers "F.Cu" "F.Mask" "F.Paste")
			(net "PVDDCR_CPU0_P0")
		)
		(pad "AU45" smd circle
			(at 6.260084 -7.649972 180)
			(size 0.450088 0.450088)
			(layers "F.Cu" "F.Mask" "F.Paste")
			(net "GND")
		)
		(pad "AU46" smd circle
			(at 7.199884 -7.649972 180)
			(size 0.450088 0.450088)
			(layers "F.Cu" "F.Mask" "F.Paste")
			(net "PVDDCR_CPU0_P0")
		)
		(pad "AU47" smd circle
			(at 8.139938 -7.649972 180)
			(size 0.450088 0.450088)
			(layers "F.Cu" "F.Mask" "F.Paste")
			(net "GND")
		)
		(pad "AU48" smd circle
			(at 9.079992 -7.649972 180)
			(size 0.450088 0.450088)
			(layers "F.Cu" "F.Mask" "F.Paste")
			(net "PVDDCR_CPU0_P0")
		)
		(pad "AU49" smd circle
			(at 10.020046 -7.649972 180)
			(size 0.450088 0.450088)
			(layers "F.Cu" "F.Mask" "F.Paste")
			(net "GND")
		)
		(pad "AU50" smd circle
			(at 10.9601 -7.649972 180)
			(size 0.450088 0.450088)
			(layers "F.Cu" "F.Mask" "F.Paste")
			(net "PVDD18_S5_P0")
		)
		(pad "AU51" smd circle
			(at 11.8999 -7.649972 180)
			(size 0.450088 0.450088)
			(layers "F.Cu" "F.Mask" "F.Paste")
			(net "GND")
		)
		(pad "AU52" smd circle
			(at 12.839954 -7.649972 180)
			(size 0.450088 0.450088)
			(layers "F.Cu" "F.Mask" "F.Paste")
			(net "PVDD18_S5_P0")
		)
		(pad "AU53" smd circle
			(at 13.780008 -7.649972 180)
			(size 0.450088 0.450088)
			(layers "F.Cu" "F.Mask" "F.Paste")
			(net "GND")
		)
		(pad "AU54" smd circle
			(at 14.720062 -7.649972 180)
			(size 0.450088 0.450088)
			(layers "F.Cu" "F.Mask" "F.Paste")
			(net "PVDD18_S5_P0")
		)
		(pad "AU55" smd circle
			(at 15.660116 -7.649972 180)
			(size 0.450088 0.450088)
			(layers "F.Cu" "F.Mask" "F.Paste")
			(net "M_C_CPU0_RESET_N")
		)
		(pad "AU56" smd circle
			(at 16.599916 -7.649972 180)
			(size 0.450088 0.450088)
			(layers "F.Cu" "F.Mask" "F.Paste")
			(net "GND")
		)
		(pad "AU57" smd circle
			(at 17.53997 -7.649972 180)
			(size 0.450088 0.450088)
			(layers "F.Cu" "F.Mask" "F.Paste")
			(net "Net_1805")
		)
		(pad "AU58" smd circle
			(at 18.480024 -7.649972 180)
			(size 0.450088 0.450088)
			(layers "F.Cu" "F.Mask" "F.Paste")
			(net "GND")
		)
		(pad "AU59" smd circle
			(at 19.420078 -7.649972 180)
			(size 0.450088 0.450088)
			(layers "F.Cu" "F.Mask" "F.Paste")
			(net "M_D_CPU0_RESET_N")
		)
		(pad "AU60" smd circle
			(at 20.359878 -7.649972 180)
			(size 0.450088 0.450088)
			(layers "F.Cu" "F.Mask" "F.Paste")
			(net "Net_1813")
		)
		(pad "AU61" smd circle
			(at 21.299932 -7.649972 180)
			(size 0.450088 0.450088)
			(layers "F.Cu" "F.Mask" "F.Paste")
			(net "GND")
		)
		(pad "AU62" smd circle
			(at 22.239986 -7.649972 180)
			(size 0.450088 0.450088)
			(layers "F.Cu" "F.Mask" "F.Paste")
			(net "M_B_CPU0_RESET_N")
		)
		(pad "AU63" smd circle
			(at 23.18004 -7.649972 180)
			(size 0.450088 0.450088)
			(layers "F.Cu" "F.Mask" "F.Paste")
			(net "GND")
		)
		(pad "AU64" smd circle
			(at 24.120094 -7.649972 180)
			(size 0.450088 0.450088)
			(layers "F.Cu" "F.Mask" "F.Paste")
			(net "Net_1797")
		)
		(pad "AU65" smd circle
			(at 25.059894 -7.649972 180)
			(size 0.450088 0.450088)
			(layers "F.Cu" "F.Mask" "F.Paste")
			(net "GND")
		)
		(pad "AU66" smd circle
			(at 25.999948 -7.649972 180)
			(size 0.450088 0.450088)
			(layers "F.Cu" "F.Mask" "F.Paste")
			(net "M_F_CPU0_RESET_N")
		)
		(pad "AU67" smd circle
			(at 26.940002 -7.649972 180)
			(size 0.450088 0.450088)
			(layers "F.Cu" "F.Mask" "F.Paste")
			(net "Net_1829")
		)
		(pad "AU68" smd circle
			(at 27.880056 -7.649972 180)
			(size 0.450088 0.450088)
			(layers "F.Cu" "F.Mask" "F.Paste")
			(net "GND")
		)
		(pad "AU69" smd circle
			(at 28.82011 -7.649972 180)
			(size 0.450088 0.450088)
			(layers "F.Cu" "F.Mask" "F.Paste")
			(net "M_E_CPU0_RESET_N")
		)
		(pad "AU70" smd circle
			(at 29.75991 -7.649972 180)
			(size 0.450088 0.450088)
			(layers "F.Cu" "F.Mask" "F.Paste")
			(net "GND")
		)
		(pad "AU71" smd circle
			(at 30.699964 -7.649972 180)
			(size 0.450088 0.450088)
			(layers "F.Cu" "F.Mask" "F.Paste")
			(net "Net_1821")
		)
		(pad "AU72" smd circle
			(at 31.640018 -7.649972 180)
			(size 0.450088 0.450088)
			(layers "F.Cu" "F.Mask" "F.Paste")
			(net "GND")
		)
		(pad "AU73" smd circle
			(at 32.580072 -7.649972 180)
			(size 0.450088 0.450088)
			(layers "F.Cu" "F.Mask" "F.Paste")
			(net "GND")
		)
		(pad "AU74" smd circle
			(at 33.519872 -7.649972 180)
			(size 0.450088 0.450088)
			(layers "F.Cu" "F.Mask" "F.Paste")
			(net "Net_1789")
		)
		(pad "AU75" smd circle
			(at 34.459926 -7.649972 180)
			(size 0.450088 0.450088)
			(layers "F.Cu" "F.Mask" "F.Paste")
			(net "GND")
		)
		(pad "AV2" smd circle
			(at -33.690052 -6.839966 180)
			(size 0.450088 0.450088)
			(layers "F.Cu" "F.Mask" "F.Paste")
			(net "Net_1837")
		)
		(pad "AV3" smd circle
			(at -32.749998 -6.839966 180)
			(size 0.450088 0.450088)
			(layers "F.Cu" "F.Mask" "F.Paste")
			(net "GND")
		)
		(pad "AV4" smd circle
			(at -31.809944 -6.839966 180)
			(size 0.450088 0.450088)
			(layers "F.Cu" "F.Mask" "F.Paste")
			(net "M_G_CPU0_SA_CS_N<1>")
		)
		(pad "AV5" smd circle
			(at -30.86989 -6.839966 180)
			(size 0.450088 0.450088)
			(layers "F.Cu" "F.Mask" "F.Paste")
			(net "PVDDCR_SOC_P0")
		)
		(pad "AV6" smd circle
			(at -29.93009 -6.839966 180)
			(size 0.450088 0.450088)
			(layers "F.Cu" "F.Mask" "F.Paste")
			(net "Net_1966")
		)
		(pad "AV7" smd circle
			(at -28.990036 -6.839966 180)
			(size 0.450088 0.450088)
			(layers "F.Cu" "F.Mask" "F.Paste")
			(net "M_K_CPU0_SA_CS_N<1>")
		)
		(pad "AV8" smd circle
			(at -28.049982 -6.839966 180)
			(size 0.450088 0.450088)
			(layers "F.Cu" "F.Mask" "F.Paste")
			(net "GND")
		)
		(pad "AV9" smd circle
			(at -27.109928 -6.839966 180)
			(size 0.450088 0.450088)
			(layers "F.Cu" "F.Mask" "F.Paste")
			(net "Net_1958")
		)
		(pad "AV10" smd circle
			(at -26.170128 -6.839966 180)
			(size 0.450088 0.450088)
			(layers "F.Cu" "F.Mask" "F.Paste")
			(net "GND")
		)
		(pad "AV11" smd circle
			(at -25.230074 -6.839966 180)
			(size 0.450088 0.450088)
			(layers "F.Cu" "F.Mask" "F.Paste")
			(net "M_L_CPU0_SA_CS_N<1>")
		)
		(pad "AV12" smd circle
			(at -24.29002 -6.839966 180)
			(size 0.450088 0.450088)
			(layers "F.Cu" "F.Mask" "F.Paste")
			(net "PVDDCR_SOC_P0")
		)
		(pad "AV13" smd circle
			(at -23.349966 -6.839966 180)
			(size 0.450088 0.450088)
			(layers "F.Cu" "F.Mask" "F.Paste")
			(net "Net_1845")
		)
		(pad "AV14" smd circle
			(at -22.409912 -6.839966 180)
			(size 0.450088 0.450088)
			(layers "F.Cu" "F.Mask" "F.Paste")
			(net "M_H_CPU0_SA_CS_N<1>")
		)
		(pad "AV15" smd circle
			(at -21.470112 -6.839966 180)
			(size 0.450088 0.450088)
			(layers "F.Cu" "F.Mask" "F.Paste")
			(net "GND")
		)
		(pad "AV16" smd circle
			(at -20.530058 -6.839966 180)
			(size 0.450088 0.450088)
			(layers "F.Cu" "F.Mask" "F.Paste")
			(net "Net_1861")
		)
		(pad "AV17" smd circle
			(at -19.590004 -6.839966 180)
			(size 0.450088 0.450088)
			(layers "F.Cu" "F.Mask" "F.Paste")
			(net "GND")
		)
		(pad "AV18" smd circle
			(at -18.64995 -6.839966 180)
			(size 0.450088 0.450088)
			(layers "F.Cu" "F.Mask" "F.Paste")
			(net "M_J_CPU0_SA_CS_N<1>")
		)
		(pad "AV19" smd circle
			(at -17.709896 -6.839966 180)
			(size 0.450088 0.450088)
			(layers "F.Cu" "F.Mask" "F.Paste")
			(net "PVDDCR_SOC_P0")
		)
		(pad "AV20" smd circle
			(at -16.770096 -6.839966 180)
			(size 0.450088 0.450088)
			(layers "F.Cu" "F.Mask" "F.Paste")
			(net "Net_1853")
		)
		(pad "AV21" smd circle
			(at -15.830042 -6.839966 180)
			(size 0.450088 0.450088)
			(layers "F.Cu" "F.Mask" "F.Paste")
			(net "M_I_CPU0_SA_CS_N<1>")
		)
		(pad "AV22" smd circle
			(at -14.889988 -6.839966 180)
			(size 0.450088 0.450088)
			(layers "F.Cu" "F.Mask" "F.Paste")
			(net "PVDDCR_SOC_P0")
		)
		(pad "AV23" smd circle
			(at -13.949934 -6.839966 180)
			(size 0.450088 0.450088)
			(layers "F.Cu" "F.Mask" "F.Paste")
			(net "GND")
		)
		(pad "AV24" smd circle
			(at -13.00988 -6.839966 180)
			(size 0.450088 0.450088)
			(layers "F.Cu" "F.Mask" "F.Paste")
			(net "PVDDCR_SOC_P0")
		)
		(pad "AV25" smd circle
			(at -12.07008 -6.839966 180)
			(size 0.450088 0.450088)
			(layers "F.Cu" "F.Mask" "F.Paste")
			(net "GND")
		)
		(pad "AV26" smd circle
			(at -11.130026 -6.839966 180)
			(size 0.450088 0.450088)
			(layers "F.Cu" "F.Mask" "F.Paste")
			(net "PVDDCR_SOC_P0")
		)
		(pad "AV27" smd circle
			(at -10.189972 -6.839966 180)
			(size 0.450088 0.450088)
			(layers "F.Cu" "F.Mask" "F.Paste")
			(net "GND")
		)
		(pad "AV28" smd circle
			(at -9.249918 -6.839966 180)
			(size 0.450088 0.450088)
			(layers "F.Cu" "F.Mask" "F.Paste")
			(net "PVDDCR_SOC_P0")
		)
	)
)
